(kicad_pcb
	(version 20260206)
	(generator "pcbnew")
	(generator_version "10.0")
	(general
		(thickness 1.6)
		(legacy_teardrops no)
	)
	(paper "A4")
	(title_block
		(title "Bryce Canyon_SCC_16316-1_OCP.brd")
		(comment 1 "Bryce Canyon / footprints 541-547 of 1561")
	)
	(layers
		(0 "F.Cu" signal "TOP")
		(4 "In1.Cu" signal "L2GND")
		(6 "In2.Cu" signal "L3")
		(8 "In3.Cu" signal "L4VCC")
		(10 "In4.Cu" signal "L5VCC")
		(12 "In5.Cu" signal "L6")
		(14 "In6.Cu" signal "L7GND")
		(2 "B.Cu" signal "BOTTOM")
		(9 "F.Adhes" user "F.Adhesive")
		(11 "B.Adhes" user "B.Adhesive")
		(13 "F.Paste" user "Package Geometry/Pastemask Top")
		(15 "B.Paste" user "Package Geometry/Pastemask Bottom")
		(5 "F.SilkS" user "Ref Des/Silkscreen Top")
		(7 "B.SilkS" user "Ref Des/Silkscreen Bottom")
		(1 "F.Mask" user "Board Geometry/Soldermask Top")
		(3 "B.Mask" user "Board Geometry/Soldermask Bottom")
		(17 "Dwgs.User" user "User.Drawings")
		(19 "Cmts.User" user "User.Comments")
		(21 "Eco1.User" user "User.Eco1")
		(23 "Eco2.User" user "User.Eco2")
		(25 "Edge.Cuts" user "Board Geometry/Outline")
		(27 "Margin" user)
		(31 "F.CrtYd" user "Package Geometry/Place Bound Top")
		(29 "B.CrtYd" user "Package Geometry/Place Bound Bottom")
		(35 "F.Fab" user "Ref Des/Assembly Top")
		(33 "B.Fab" user "Ref Des/Assembly Bottom")
	)
	(footprint ""
		(layer "F.Cu")
		(at 165.4556 -88.0618 90)
		(property "Reference" "C643"
			(at 0 0 90)
			(layer "F.SilkS")
			(hide yes)
			(effects
				(font
					(size 1.27 1.27)
				)
			)
		)
		(property "Value" "SC10U16V5KX-7-GP-U"
			(at -0.0762 -6.1214 90)
			(unlocked yes)
			(layer "F.Fab")
			(hide yes)
			(effects
				(font
					(size 1.016 1.016)
					(thickness 0.1524)
				)
			)
		)
		(property "Device Type" "C805H58"
			(at -0.0762 -8.1534 90)
			(unlocked yes)
			(layer "F.Fab")
			(hide yes)
			(effects
				(font
					(size 1.016 1.016)
					(thickness 0.1524)
				)
			)
		)
		(duplicate_pad_numbers_are_jumpers no)
		(fp_line
			(start 0.635 0)
			(end -0.635 0)
			(stroke
				(width 0.508)
				(type default)
			)
			(layer "F.SilkS")
		)
		(fp_rect
			(start -0.9652 1.778)
			(end 0.9652 -1.778)
			(stroke
				(width 0)
				(type default)
			)
			(fill no)
			(layer "F.CrtYd")
		)
		(fp_poly
			(pts
				(xy -0.9652 -1.778) (xy 0.9652 -1.778) (xy 0.9652 1.778) (xy -0.9652 1.778)
			)
			(stroke
				(width 0)
				(type default)
			)
			(fill no)
			(layer "F.Fab")
		)
		(pad "1" smd rect
			(at 0 -0.9652 90)
			(size 1.397 1.143)
			(layers "F.Cu" "F.Mask" "F.Paste")
			(net "P12V_SYBY_VDD_U6")
		)
		(pad "2" smd rect
			(at 0 0.9652 90)
			(size 1.397 1.143)
			(layers "F.Cu" "F.Mask" "F.Paste")
			(net "GND")
		)
	)
	(footprint ""
		(layer "F.Cu")
		(at 15.0114 -99.3267 -90)
		(property "Reference" "C732"
			(at 0 0 270)
			(layer "F.SilkS")
			(hide yes)
			(effects
				(font
					(size 1.27 1.27)
				)
			)
		)
		(property "Value" "SCD1U16V2KX-3GP"
			(at 1.1811 -2.7051 270)
			(unlocked yes)
			(layer "F.Fab")
			(hide yes)
			(effects
				(font
					(size 1.016 1.016)
					(thickness 0.1524)
				)
			)
		)
		(property "Device Type" "C402H22"
			(at 1.1811 -4.2291 270)
			(unlocked yes)
			(layer "F.Fab")
			(hide yes)
			(effects
				(font
					(size 1.016 1.016)
					(thickness 0.1524)
				)
			)
		)
		(duplicate_pad_numbers_are_jumpers no)
		(fp_rect
			(start -0.4318 0.9525)
			(end 0.4318 -0.9525)
			(stroke
				(width 0)
				(type default)
			)
			(fill no)
			(layer "F.CrtYd")
		)
		(fp_rect
			(start -0.4318 0.9525)
			(end 0.4318 -0.9525)
			(stroke
				(width 0)
				(type default)
			)
			(fill no)
			(layer "F.Fab")
		)
		(pad "1" smd custom
			(at 0 -0.4445 270)
			(size 0.1524 0.1524)
			(layers "F.Cu" "F.Mask" "F.Paste")
			(net "P3V3")
			(options
				(clearance outline)
				(anchor circle)
			)
			(primitives
				(gr_poly
					(pts
						(arc
							(start 0.3048 -0.2032)
							(mid 0.275042 -0.275042)
							(end 0.2032 -0.3048)
						)
						(arc
							(start -0.2032 -0.3048)
							(mid -0.275042 -0.275042)
							(end -0.3048 -0.2032)
						)
						(arc
							(start -0.3048 0.2032)
							(mid -0.275042 0.275042)
							(end -0.2032 0.3048)
						)
						(arc
							(start 0.2032 0.3048)
							(mid 0.275042 0.275042)
							(end 0.3048 0.2032)
						)
					)
					(width 0)
					(fill yes)
				)
			)
		)
		(pad "2" smd custom
			(at 0 0.4445 270)
			(size 0.1524 0.1524)
			(layers "F.Cu" "F.Mask" "F.Paste")
			(net "GND")
			(options
				(clearance outline)
				(anchor circle)
			)
			(primitives
				(gr_poly
					(pts
						(arc
							(start 0.3048 -0.2032)
							(mid 0.275042 -0.275042)
							(end 0.2032 -0.3048)
						)
						(arc
							(start -0.2032 -0.3048)
							(mid -0.275042 -0.275042)
							(end -0.3048 -0.2032)
						)
						(arc
							(start -0.3048 0.2032)
							(mid -0.275042 0.275042)
							(end -0.2032 0.3048)
						)
						(arc
							(start 0.2032 0.3048)
							(mid 0.275042 0.275042)
							(end 0.3048 0.2032)
						)
					)
					(width 0)
					(fill yes)
				)
			)
		)
	)
	(footprint ""
		(layer "F.Cu")
		(at 24.96693 -93.622622)
		(property "Reference" "R448"
			(at 0 0 0)
			(layer "F.SilkS")
			(hide yes)
			(effects
				(font
					(size 1.27 1.27)
				)
			)
		)
		(property "Value" "1KR2F-3-GP"
			(at 0.064008 -3.993896 0)
			(unlocked yes)
			(layer "F.Fab")
			(hide yes)
			(effects
				(font
					(size 1.016 1.016)
					(thickness 0.1524)
				)
			)
		)
		(property "Device Type" "R402H16"
			(at 0.064008 -5.517896 0)
			(unlocked yes)
			(layer "F.Fab")
			(hide yes)
			(effects
				(font
					(size 1.016 1.016)
					(thickness 0.1524)
				)
			)
		)
		(duplicate_pad_numbers_are_jumpers no)
		(fp_line
			(start -0.508 -0.9398)
			(end -0.508 0.9398)
			(stroke
				(width 0.1524)
				(type default)
			)
			(layer "F.SilkS")
		)
		(fp_line
			(start 0.508 -0.9398)
			(end -0.508 -0.9398)
			(stroke
				(width 0.1524)
				(type default)
			)
			(layer "F.SilkS")
		)
		(fp_rect
			(start -0.508 0.9398)
			(end 0.508 -0.9398)
			(stroke
				(width 0)
				(type default)
			)
			(fill no)
			(layer "F.CrtYd")
		)
		(fp_rect
			(start -0.508 0.9398)
			(end 0.508 -0.9398)
			(stroke
				(width 0)
				(type default)
			)
			(fill no)
			(layer "F.Fab")
		)
		(pad "1" smd custom
			(at 0 -0.4445)
			(size 0.1397 0.1397)
			(layers "F.Cu" "F.Mask" "F.Paste")
			(net "P3V3")
			(options
				(clearance outline)
				(anchor circle)
			)
			(primitives
				(gr_poly
					(pts
						(arc
							(start -0.1778 -0.2794)
							(mid -0.249642 -0.249642)
							(end -0.2794 -0.1778)
						)
						(arc
							(start -0.2794 0.1778)
							(mid -0.249642 0.249642)
							(end -0.1778 0.2794)
						)
						(arc
							(start 0.1778 0.2794)
							(mid 0.249642 0.249642)
							(end 0.2794 0.1778)
						)
						(arc
							(start 0.2794 -0.1778)
							(mid 0.249642 -0.249642)
							(end 0.1778 -0.2794)
						)
					)
					(width 0)
					(fill yes)
				)
			)
		)
		(pad "2" smd custom
			(at 0 0.4445)
			(size 0.1397 0.1397)
			(layers "F.Cu" "F.Mask" "F.Paste")
			(net "I2C_BMC_RMT_SCL1")
			(options
				(clearance outline)
				(anchor circle)
			)
			(primitives
				(gr_poly
					(pts
						(arc
							(start -0.1778 -0.2794)
							(mid -0.249642 -0.249642)
							(end -0.2794 -0.1778)
						)
						(arc
							(start -0.2794 0.1778)
							(mid -0.249642 0.249642)
							(end -0.1778 0.2794)
						)
						(arc
							(start 0.1778 0.2794)
							(mid 0.249642 0.249642)
							(end 0.2794 0.1778)
						)
						(arc
							(start 0.2794 -0.1778)
							(mid 0.249642 -0.249642)
							(end 0.1778 -0.2794)
						)
					)
					(width 0)
					(fill yes)
				)
			)
		)
	)
	(footprint ""
		(layer "F.Cu")
		(at 140.054076 -84.705952)
		(property "Reference" "R48"
			(at 0 0 0)
			(layer "F.SilkS")
			(hide yes)
			(effects
				(font
					(size 1.27 1.27)
				)
			)
		)
		(property "Value" "4K7R2F-GP"
			(at 0.064008 -3.993896 0)
			(unlocked yes)
			(layer "F.Fab")
			(hide yes)
			(effects
				(font
					(size 1.016 1.016)
					(thickness 0.1524)
				)
			)
		)
		(property "Device Type" "R402H16"
			(at 0.064008 -5.517896 0)
			(unlocked yes)
			(layer "F.Fab")
			(hide yes)
			(effects
				(font
					(size 1.016 1.016)
					(thickness 0.1524)
				)
			)
		)
		(duplicate_pad_numbers_are_jumpers no)
		(fp_line
			(start -0.508 -0.9398)
			(end -0.508 0.9398)
			(stroke
				(width 0.1524)
				(type default)
			)
			(layer "F.SilkS")
		)
		(fp_line
			(start 0.508 -0.9398)
			(end -0.508 -0.9398)
			(stroke
				(width 0.1524)
				(type default)
			)
			(layer "F.SilkS")
		)
		(fp_rect
			(start -0.508 0.9398)
			(end 0.508 -0.9398)
			(stroke
				(width 0)
				(type default)
			)
			(fill no)
			(layer "F.CrtYd")
		)
		(fp_rect
			(start -0.508 0.9398)
			(end 0.508 -0.9398)
			(stroke
				(width 0)
				(type default)
			)
			(fill no)
			(layer "F.Fab")
		)
		(pad "1" smd custom
			(at 0 -0.4445)
			(size 0.1397 0.1397)
			(layers "F.Cu" "F.Mask" "F.Paste")
			(net "P1V8_E")
			(options
				(clearance outline)
				(anchor circle)
			)
			(primitives
				(gr_poly
					(pts
						(arc
							(start -0.1778 -0.2794)
							(mid -0.249642 -0.249642)
							(end -0.2794 -0.1778)
						)
						(arc
							(start -0.2794 0.1778)
							(mid -0.249642 0.249642)
							(end -0.1778 0.2794)
						)
						(arc
							(start 0.1778 0.2794)
							(mid 0.249642 0.249642)
							(end 0.2794 0.1778)
						)
						(arc
							(start 0.2794 -0.1778)
							(mid 0.249642 -0.249642)
							(end 0.1778 -0.2794)
						)
					)
					(width 0)
					(fill yes)
				)
			)
		)
		(pad "2" smd custom
			(at 0 0.4445)
			(size 0.1397 0.1397)
			(layers "F.Cu" "F.Mask" "F.Paste")
			(net "I2C_BMC_LOC_SCL0_LS")
			(options
				(clearance outline)
				(anchor circle)
			)
			(primitives
				(gr_poly
					(pts
						(arc
							(start -0.1778 -0.2794)
							(mid -0.249642 -0.249642)
							(end -0.2794 -0.1778)
						)
						(arc
							(start -0.2794 0.1778)
							(mid -0.249642 0.249642)
							(end -0.1778 0.2794)
						)
						(arc
							(start 0.1778 0.2794)
							(mid 0.249642 0.249642)
							(end 0.2794 0.1778)
						)
						(arc
							(start 0.2794 -0.1778)
							(mid 0.249642 -0.249642)
							(end 0.1778 -0.2794)
						)
					)
					(width 0)
					(fill yes)
				)
			)
		)
	)
	(footprint ""
		(layer "F.Cu")
		(at 10.5918 -36.195 180)
		(property "Reference" "Q23"
			(at 0 0 180)
			(layer "F.SilkS")
			(hide yes)
			(effects
				(font
					(size 1.27 1.27)
				)
			)
		)
		(property "Value" "PSMN0R9-25YLC-GP"
			(at -4.2799 -0.4572 180)
			(unlocked yes)
			(layer "F.Fab")
			(hide yes)
			(effects
				(font
					(size 1.016 1.016)
					(thickness 0.1524)
				)
			)
		)
		(property "Device Type" "LFPAK-5PH48-U"
			(at -4.2799 -1.9812 180)
			(unlocked yes)
			(layer "F.Fab")
			(hide yes)
			(effects
				(font
					(size 1.016 1.016)
					(thickness 0.1524)
				)
			)
		)
		(duplicate_pad_numbers_are_jumpers no)
		(fp_line
			(start 2.7559 1.0668)
			(end 2.7559 -6.5532)
			(stroke
				(width 0.1524)
				(type default)
			)
			(layer "F.SilkS")
		)
		(fp_line
			(start 2.7559 -6.5532)
			(end -2.7559 -6.5532)
			(stroke
				(width 0.1524)
				(type default)
			)
			(layer "F.SilkS")
		)
		(fp_line
			(start -1.7272 1.1684)
			(end -2.1082 1.1684)
			(stroke
				(width 0.3302)
				(type default)
			)
			(layer "F.SilkS")
		)
		(fp_line
			(start -2.7559 1.0668)
			(end 2.7559 1.0668)
			(stroke
				(width 0.1524)
				(type default)
			)
			(layer "F.SilkS")
		)
		(fp_line
			(start -2.7559 -6.5532)
			(end -2.7559 1.0668)
			(stroke
				(width 0.1524)
				(type default)
			)
			(layer "F.SilkS")
		)
		(fp_poly
			(pts
				(xy -2.3368 1.5748) (xy -1.905 1.143) (xy -1.4732 1.5748)
			)
			(stroke
				(width 0)
				(type default)
			)
			(fill yes)
			(layer "F.SilkS")
		)
		(fp_poly
			(pts
				(xy 0.3302 -1.09601) (xy 2.5019 -1.09601) (xy 2.5019 -3.36931) (xy 0.3302 -3.36931)
			)
			(stroke
				(width 0)
				(type default)
			)
			(fill yes)
			(layer "F.Paste")
		)
		(fp_poly
			(pts
				(xy 0.3302 -4.02971) (xy 2.5019 -4.02971) (xy 2.5019 -6.30301) (xy 0.3302 -6.30301)
			)
			(stroke
				(width 0)
				(type default)
			)
			(fill yes)
			(layer "F.Paste")
		)
		(fp_poly
			(pts
				(xy -2.5019 -1.09601) (xy -0.3302 -1.09601) (xy -0.3302 -3.36931) (xy -2.5019 -3.36931)
			)
			(stroke
				(width 0)
				(type default)
			)
			(fill yes)
			(layer "F.Paste")
		)
		(fp_poly
			(pts
				(xy -2.5019 -4.02971) (xy -0.3302 -4.02971) (xy -0.3302 -6.30301) (xy -2.5019 -6.30301)
			)
			(stroke
				(width 0)
				(type default)
			)
			(fill yes)
			(layer "F.Paste")
		)
		(fp_rect
			(start -2.4511 0.3048)
			(end 2.4511 -5.6896)
			(stroke
				(width 0)
				(type default)
			)
			(fill no)
			(layer "F.CrtYd")
		)
		(fp_poly
			(pts
				(xy -3.0099 1.3208) (xy -3.0099 -6.8072) (xy 3.0099 -6.8072) (xy 3.0099 -1.016) (xy 2.4511 -1.016)
				(xy 2.4511 -5.6896) (xy -2.4511 -5.6896) (xy -2.4511 0.3048) (xy 2.4511 0.3048) (xy 2.4511 -1.0033)
				(xy 3.0099 -1.0033) (xy 3.0099 1.3208)
			)
			(stroke
				(width 0)
				(type default)
			)
			(fill no)
			(layer "F.CrtYd")
		)
		(fp_rect
			(start -3.0099 1.3208)
			(end 3.0099 -6.8072)
			(stroke
				(width 0)
				(type default)
			)
			(fill no)
			(layer "F.Fab")
		)
		(pad "1" smd rect
			(at -1.905 0 180)
			(size 0.762 1.6256)
			(layers "F.Cu" "F.Mask" "F.Paste")
			(net "P12V_STBY_SCC")
		)
		(pad "2" smd rect
			(at -0.635 0 180)
			(size 0.762 1.6256)
			(layers "F.Cu" "F.Mask" "F.Paste")
			(net "P12V_STBY_SCC")
		)
		(pad "3" smd rect
			(at 0.635 0 180)
			(size 0.762 1.6256)
			(layers "F.Cu" "F.Mask" "F.Paste")
			(net "P12V_STBY_SCC")
		)
		(pad "4" smd rect
			(at 1.905 0 180)
			(size 0.762 1.6256)
			(layers "F.Cu" "F.Mask" "F.Paste")
			(net "MB0_12V_CTRL_GATE1")
		)
		(pad "5" smd rect
			(at 0 -3.69951 180)
			(size 5.0038 5.207)
			(layers "F.Cu" "F.Mask" "F.Paste")
			(net "MB0_P12V_MAIN_R")
		)
	)
	(footprint ""
		(layer "F.Cu")
		(at 149.4282 -123.6091 -90)
		(property "Reference" "R377"
			(at 0 0 270)
			(layer "F.SilkS")
			(hide yes)
			(effects
				(font
					(size 1.27 1.27)
				)
			)
		)
		(property "Value" "15KR2F-GP"
			(at 0.064008 -3.993896 270)
			(unlocked yes)
			(layer "F.Fab")
			(hide yes)
			(effects
				(font
					(size 1.016 1.016)
					(thickness 0.1524)
				)
			)
		)
		(property "Device Type" "R402H16"
			(at 0.064008 -5.517896 270)
			(unlocked yes)
			(layer "F.Fab")
			(hide yes)
			(effects
				(font
					(size 1.016 1.016)
					(thickness 0.1524)
				)
			)
		)
		(duplicate_pad_numbers_are_jumpers no)
		(fp_line
			(start -0.508 -0.9398)
			(end -0.508 0.9398)
			(stroke
				(width 0.1524)
				(type default)
			)
			(layer "F.SilkS")
		)
		(fp_line
			(start 0.508 -0.9398)
			(end -0.508 -0.9398)
			(stroke
				(width 0.1524)
				(type default)
			)
			(layer "F.SilkS")
		)
		(fp_rect
			(start -0.508 0.9398)
			(end 0.508 -0.9398)
			(stroke
				(width 0)
				(type default)
			)
			(fill no)
			(layer "F.CrtYd")
		)
		(fp_rect
			(start -0.508 0.9398)
			(end 0.508 -0.9398)
			(stroke
				(width 0)
				(type default)
			)
			(fill no)
			(layer "F.Fab")
		)
		(pad "1" smd custom
			(at 0 -0.4445 270)
			(size 0.1397 0.1397)
			(layers "F.Cu" "F.Mask" "F.Paste")
			(net "P1V5_E_VFB")
			(options
				(clearance outline)
				(anchor circle)
			)
			(primitives
				(gr_poly
					(pts
						(arc
							(start -0.1778 -0.2794)
							(mid -0.249642 -0.249642)
							(end -0.2794 -0.1778)
						)
						(arc
							(start -0.2794 0.1778)
							(mid -0.249642 0.249642)
							(end -0.1778 0.2794)
						)
						(arc
							(start 0.1778 0.2794)
							(mid 0.249642 0.249642)
							(end 0.2794 0.1778)
						)
						(arc
							(start 0.2794 -0.1778)
							(mid 0.249642 -0.249642)
							(end 0.1778 -0.2794)
						)
					)
					(width 0)
					(fill yes)
				)
			)
		)
		(pad "2" smd custom
			(at 0 0.4445 270)
			(size 0.1397 0.1397)
			(layers "F.Cu" "F.Mask" "F.Paste")
			(net "P1V5_E_VFB_R")
			(options
				(clearance outline)
				(anchor circle)
			)
			(primitives
				(gr_poly
					(pts
						(arc
							(start -0.1778 -0.2794)
							(mid -0.249642 -0.249642)
							(end -0.2794 -0.1778)
						)
						(arc
							(start -0.2794 0.1778)
							(mid -0.249642 0.249642)
							(end -0.1778 0.2794)
						)
						(arc
							(start 0.1778 0.2794)
							(mid 0.249642 0.249642)
							(end 0.2794 0.1778)
						)
						(arc
							(start 0.2794 -0.1778)
							(mid 0.249642 -0.249642)
							(end 0.1778 -0.2794)
						)
					)
					(width 0)
					(fill yes)
				)
			)
		)
	)
	(footprint ""
		(layer "F.Cu")
		(at 181.229 -55.245 -90)
		(property "Reference" "R229"
			(at 0 0 270)
			(layer "F.SilkS")
			(hide yes)
			(effects
				(font
					(size 1.27 1.27)
				)
			)
		)
		(property "Value" "10KR2F-2-GP"
			(at 0.064008 -3.993896 270)
			(unlocked yes)
			(layer "F.Fab")
			(hide yes)
			(effects
				(font
					(size 1.016 1.016)
					(thickness 0.1524)
				)
			)
		)
		(property "Device Type" "R402H16"
			(at 0.064008 -5.517896 270)
			(unlocked yes)
			(layer "F.Fab")
			(hide yes)
			(effects
				(font
					(size 1.016 1.016)
					(thickness 0.1524)
				)
			)
		)
		(duplicate_pad_numbers_are_jumpers no)
		(fp_line
			(start -0.508 -0.9398)
			(end -0.508 0.9398)
			(stroke
				(width 0.1524)
				(type default)
			)
			(layer "F.SilkS")
		)
		(fp_line
			(start 0.508 -0.9398)
			(end -0.508 -0.9398)
			(stroke
				(width 0.1524)
				(type default)
			)
			(layer "F.SilkS")
		)
		(fp_rect
			(start -0.508 0.9398)
			(end 0.508 -0.9398)
			(stroke
				(width 0)
				(type default)
			)
			(fill no)
			(layer "F.CrtYd")
		)
		(fp_rect
			(start -0.508 0.9398)
			(end 0.508 -0.9398)
			(stroke
				(width 0)
				(type default)
			)
			(fill no)
			(layer "F.Fab")
		)
		(pad "1" smd custom
			(at 0 -0.4445 270)
			(size 0.1397 0.1397)
			(layers "F.Cu" "F.Mask" "F.Paste")
			(net "P1V8_C")
			(options
				(clearance outline)
				(anchor circle)
			)
			(primitives
				(gr_poly
					(pts
						(arc
							(start -0.1778 -0.2794)
							(mid -0.249642 -0.249642)
							(end -0.2794 -0.1778)
						)
						(arc
							(start -0.2794 0.1778)
							(mid -0.249642 0.249642)
							(end -0.1778 0.2794)
						)
						(arc
							(start 0.1778 0.2794)
							(mid 0.249642 0.249642)
							(end 0.2794 0.1778)
						)
						(arc
							(start 0.2794 -0.1778)
							(mid 0.249642 -0.249642)
							(end 0.1778 -0.2794)
						)
					)
					(width 0)
					(fill yes)
				)
			)
		)
		(pad "2" smd custom
			(at 0 0.4445 270)
			(size 0.1397 0.1397)
			(layers "F.Cu" "F.Mask" "F.Paste")
			(net "XM_RB")
			(options
				(clearance outline)
				(anchor circle)
			)
			(primitives
				(gr_poly
					(pts
						(arc
							(start -0.1778 -0.2794)
							(mid -0.249642 -0.249642)
							(end -0.2794 -0.1778)
						)
						(arc
							(start -0.2794 0.1778)
							(mid -0.249642 0.249642)
							(end -0.1778 0.2794)
						)
						(arc
							(start 0.1778 0.2794)
							(mid 0.249642 0.249642)
							(end 0.2794 0.1778)
						)
						(arc
							(start 0.2794 -0.1778)
							(mid 0.249642 -0.249642)
							(end 0.1778 -0.2794)
						)
					)
					(width 0)
					(fill yes)
				)
			)
		)
	)
)
